FILE_TYPE = CONNECTIVITY;
{Allegro Design Entry HDL 17.4-2019 S026 (4007227) 1/17/2022}
"PAGE_NUMBER" = 8;
0"NC";
END.
